#ISCELL
  mstr_misc dns *
  *
#ISCELL
  mstr_symbols intel_corp_bpage *
  *
#ISCELL
  mstr_symbols pvddq_def *
  page220_i109
#CELL
  mstr_discrete cap *
  page220_i110
#ISCELL
  mstr_symbols gnd *
  page220_i114
#ISCELL
  mstr_symbols vcc_core *
  page220_i120
#ISCELL
  mstr_symbols gnd *
  page220_i123
#CELL
  mstr_discrete inductor *
  page220_i124
#CELL
  mstr_discrete capp *
  page220_i175
#ISCELL
  mstr_symbols p12v_stby *
  page220_i176
#CELL
  mstr_discrete cap *
  page220_i177
#CELL
  mstr_discrete cap *
  page220_i179
#CELL
  mstr_discrete cap *
  page220_i180
#ISCELL
  mstr_symbols gnd *
  page220_i181
#CELL
  mstr_discrete cap *
  page220_i182
#CELL
  mstr_discrete cap *
  page220_i183
#CELL
  mstr_discrete cap *
  page220_i184
#ISCELL
  mstr_symbols pvddq_def *
  page220_i185
#ISCELL
  mstr_symbols pvddq_def *
  page220_i189
#ISCELL
  mstr_symbols gnd *
  page220_i191
#CELL
  dev_discrete cap_a *
  page220_i192
#CELL
  dev_discrete cap_a *
  page220_i193
#CELL
  dev_discrete cap_a *
  page220_i194
#CELL
  dev_discrete cap_a *
  page220_i195
#CELL
  dev_discrete cap_a *
  page220_i196
#CELL
  dev_discrete cap_a *
  page220_i197
#CELL
  dev_discrete cap_a *
  page220_i198
#CELL
  dev_discrete cap_a *
  page220_i199
#CELL
  dev_discrete cap_a *
  page220_i200
#ISCELL
  mstr_symbols pvddq_def *
  page220_i201
#ISCELL
  mstr_symbols gnd *
  page220_i202
#CELL
  dev_discrete cap_a *
  page220_i203
#CELL
  dev_discrete cap_a *
  page220_i204
#CELL
  dev_discrete cap_a *
  page220_i205
#CELL
  dev_discrete cap_a *
  page220_i206
#CELL
  dev_discrete cap_a *
  page220_i207
#CELL
  dev_discrete cap_a *
  page220_i208
#CELL
  dev_discrete cap_a *
  page220_i209
#CELL
  dev_discrete cap_a *
  page220_i210
#CELL
  dev_discrete cap_a *
  page220_i211
#CELL
  dev_discrete cap_a *
  page220_i212
#CELL
  dev_discrete cap_a *
  page220_i213
#CELL
  dev_discrete cap_a *
  page220_i214
#CELL
  dev_discrete cap_a *
  page220_i215
#CELL
  dev_discrete cap_a *
  page220_i216
#CELL
  dev_discrete cap_a *
  page220_i217
#ISCELL
  mstr_symbols pvddq_def *
  page220_i218
#CELL
  dev_discrete cap_a *
  page220_i219
#ISCELL
  mstr_symbols gnd *
  page220_i220
#CELL
  dev_discrete cap_a *
  page220_i221
#CELL
  dev_discrete cap_a *
  page220_i222
#CELL
  dev_discrete cap_a *
  page220_i223
#CELL
  dev_discrete cap_a *
  page220_i224
#CELL
  dev_discrete cap_a *
  page220_i225
#CELL
  dev_discrete cap_a *
  page220_i226
#CELL
  dev_discrete cap_a *
  page220_i227
#CELL
  dev_discrete cap_a *
  page220_i228
#CELL
  dev_discrete cap_a *
  page220_i229
#CELL
  dev_discrete cap_a *
  page220_i230
#CELL
  dev_discrete cap_a *
  page220_i231
#CELL
  dev_discrete cap_a *
  page220_i232
#CELL
  dev_discrete cap_a *
  page220_i233
#CELL
  dev_discrete cap_a *
  page220_i234
#ISCELL
  mstr_symbols pvddq_def *
  page220_i235
#CELL
  dev_discrete cap_a *
  page220_i236
#CELL
  dev_discrete cap_a *
  page220_i237
#ISCELL
  mstr_symbols gnd *
  page220_i238
#CELL
  mstr_misc shunt *
  page220_i239
#CELL
  mstr_misc shunt *
  page220_i240
#CELL
  mstr_discrete res *
  page220_i58
#ISCELL
  mstr_symbols gnd *
  page220_i65
#ISCELL
  mstr_standard offpage *
  page220_i70
#ISCELL
  mstr_standard offpage *
  page220_i72
#ISCELL
  mstr_symbols pvddq_def *
  page220_i73
#CELL
  mstr_discrete res *
  page220_i74
#CELL
  mstr_discrete capp *
  page220_i75
#CELL
  mstr_discrete capp *
  page220_i76
#CELL
  mstr_discrete capp *
  page220_i77
#CELL
  mstr_discrete capp *
  page220_i78
#ISCELL
  mstr_symbols pvddq_def *
  page220_i80
#ISCELL
  mstr_symbols gnd *
  page220_i81
#CELL
  mstr_discrete cap *
  page220_i82
#CELL
  mstr_discrete cap *
  page220_i83
#CELL
  mstr_discrete cap *
  page220_i88
#CELL
  mstr_discrete cap *
  page220_i89
#CELL
  mstr_discrete cap *
  page220_i90
#CELL
  mstr_discrete cap *
  page220_i91
#CELL
  mstr_discrete cap *
  page220_i92
#ISCELL
  mstr_symbols pvddq_def *
  page220_i93
#ISCELL
  mstr_symbols gnd *
  page220_i94
